FILE_TYPE = CONNECTIVITY;
{Allegro Design Entry HDL 16.6-p007 (v16-6-112F) 10/10/2012}
"PAGE_NUMBER" = 126;
0"NC";
1"GND\g";
2"P3V3_STBY\g";
3"GND\g";
4"P3V3_STBY\g";
5"GND\g";
6"P3V3_STBY\g";
7"P3V3_STBY\g";
8"FM_FLASH_ATTACH_CFG_STRAP";
9"RST_RSMRST_DLY";
10"IRQ_SML0_ALERT_N";
11"FM_OC_DETECT_EN_N";
12"FM_PCH_BMC_THERMTRIP_EXI_STRAP_N";
%"RES"
"2","(-6325,4175)","0","mstr_discrete","I10";
;
CDS_SEC"1"
ROOM"SB_HEADERS"
CDS_LOCATION"R2N10"
BOM_COST"SB"
CDS_LIB"mstr_discrete"
SEC"1"
SEC_TYPE"0402"
LOCATION"R2N10"
PART_NUMBER"G21796-072"
VALUE"4.75K"
TOLERANCE"1%"
PACK_TYPE"0402"
MATERIAL"CHIP"
WATTAGE"1/16W";
"A"
$PN"1"7;
"B"
$PN"2"12;
%"RES"
"2","(-6200,2775)","0","mstr_discrete","I12";
;
CDS_SEC"1"
ROOM"BMC_MISC"
CDS_LIB"mstr_discrete"
CDS_LOCATION"R1D35"
BOM_COST"SM_CONTROLLER"
SEC_TYPE"0402"
SEC"1"
MATERIAL"CHIP"
LOCATION"R1D35"
VALUE"4.75K"
WATTAGE"1/16W"
PART_NUMBER"G21796-072"
TOLERANCE"1%"
PACK_TYPE"0402";
"A"
$PN"1"6;
"B"
$PN"2"11;
%"FET_N"
"8","(-3625,3925)","0","mstr_discrete","I13";
;
CDS_SEC"1"
CDS_LOCATION"Q8E2"
PACK_TYPE"SOT23LF"
CDS_LIB"mstr_discrete"
SEC"1"
SEC_TYPE"SOT23LF"
LOCATION"Q8E2"
PART_NUMBER"C79254-001"
VALUE"2N7002"
MATERIAL"FET";
"GATE"
$PN"1"9;
"DRN"
$PN"3"10;
"SRC"
$PN"2"1;
%"GND"
"1","(-3625,3575)","0","mstr_symbols","I14";
;
VOLTAGE"0.0V"
HDL_POWER"GND"
ROOM"SB"
BODY_TYPE"PLUMBING"
CDS_LIB"mstr_symbols"
BOM_COST"SB"
SIZE"1B";
"A\NAC"1;
%"P3V3_STBY"
"1","(-3625,4650)","0","mstr_symbols","I16";
;
VOLTAGE"3.3V"
HDL_POWER"P3V3_STBY"
BODY_TYPE"PLUMBING"
CDS_LIB"mstr_symbols"
SIZE"1B";
"G\NAC"2;
%"RES"
"2","(-3625,4425)","0","mstr_discrete","I20";
;
CDS_SEC"1"
ROOM"BMC_MISC"
CDS_LIB"mstr_discrete"
BOM_COST"SM_CONTROLLER"
SEC_TYPE"0402"
SEC"1"
CDS_LOCATION"R8C9"
LOCATION"R8C9"
PART_NUMBER"G21796-072"
VALUE"4.75K"
TOLERANCE"1%"
MATERIAL"CHIP"
WATTAGE"1/16W"
PACK_TYPE"0402";
"A"
$PN"1"2;
"B"
$PN"2"10;
%"RES"
"2","(-4525,2725)","0","mstr_discrete","I22";
;
CDS_SEC"1"
CDS_LOCATION"R3P62"
CDS_LIB"mstr_discrete"
SEC"1"
SEC_TYPE"0402"
PART_NUMBER"G21796-072"
MATERIAL"EMPTY"
WATTAGE"1/16W"
LOCATION"R3P62"
VALUE"4.75K"
TOLERANCE"1%"
PACK_TYPE"0402";
"A"
$PN"1"4;
"B"
$PN"2"8;
%"RES"
"2","(-4525,2275)","0","mstr_discrete","I23";
;
CDS_SEC"1"
CDS_LOCATION"R3P64"
CDS_LIB"mstr_discrete"
SEC_TYPE"0402"
SEC"1"
MATERIAL"EMPTY"
LOCATION"R3P64"
PART_NUMBER"G21796-026"
VALUE"1.00K"
TOLERANCE"1%"
PACK_TYPE"0402"
WATTAGE"1/16W";
"A"
$PN"1"8;
"B"
$PN"2"3;
%"GND"
"1","(-4525,2050)","0","mstr_symbols","I24";
;
VOLTAGE"0.0V"
HDL_POWER"GND"
BODY_TYPE"PLUMBING"
SIZE"1B"
CDS_LIB"mstr_symbols";
"A\NAC"3;
%"P3V3_STBY"
"1","(-4525,2975)","0","mstr_symbols","I25";
;
VOLTAGE"3.3V"
HDL_POWER"P3V3_STBY"
CDS_LIB"mstr_symbols"
BODY_TYPE"PLUMBING"
SIZE"1B";
"G\NAC"4;
%"GND"
"1","(-6200,2100)","0","mstr_symbols","I5";
;
VOLTAGE"0.0V"
HDL_POWER"GND"
ROOM"SB"
CDS_LIB"mstr_symbols"
BODY_TYPE"PLUMBING"
BOM_COST"SB"
SIZE"1B";
"A\NAC"5;
%"RES"
"2","(-6200,2350)","0","mstr_discrete","I6";
;
CDS_SEC"1"
ROOM"SB"
CDS_LIB"mstr_discrete"
CDS_LOCATION"R7D19"
BOM_COST"SB"
SEC_TYPE"0402"
SEC"1"
PART_NUMBER"G21796-026"
MATERIAL"EMPTY"
LOCATION"R7D19"
VALUE"1.00K"
TOLERANCE"1%"
PACK_TYPE"0402"
WATTAGE"1/16W";
"A"
$PN"1"11;
"B"
$PN"2"5;
%"P3V3_STBY"
"1","(-6200,3000)","0","mstr_symbols","I7";
;
VOLTAGE"3.3V"
HDL_POWER"P3V3_STBY"
SIZE"1B"
CDS_LIB"mstr_symbols"
BODY_TYPE"PLUMBING";
"G\NAC"6;
%"P3V3_STBY"
"1","(-6325,4400)","0","mstr_symbols","I9";
;
VOLTAGE"3.3V"
HDL_POWER"P3V3_STBY"
CDS_LIB"mstr_symbols"
SIZE"1B"
BODY_TYPE"PLUMBING";
"G\NAC"7;
END.
